#ISCELL
  logical_power design_note *
  *
#ISCELL
  pure_quanta quanta_title_block_c *
  *
#ISCELL
  logical_power universal_gnd *
  page223_i10
#CELL
  pure_quanta q_res *
  page223_i100
#CELL
  pure_quanta q_res *
  page223_i101
#CELL
  pure_quanta q_res *
  page223_i102
#CELL
  pure_quanta mosfet_nch_dual *
  page223_i104
#CELL
  pure_quanta mosfet_nch_dual *
  page223_i106
#CELL
  pure_quanta mosfet_nch_dual *
  page223_i108
#CELL
  pure_quanta mosfet_nch_dual *
  page223_i109
#ISCELL
  logical_power universal_power *
  page223_i11
#CELL
  pure_quanta q_res *
  page223_i12
#ISCELL
  logical_power universal_power *
  page223_i16
#ISCELL
  logical_power universal_gnd *
  page223_i17
#CELL
  pure_quanta q_cap *
  page223_i18
#ISCELL
  logical_power universal_power *
  page223_i19
#CELL
  pure_quanta q_cap *
  page223_i20
#ISCELL
  logical_power universal_gnd *
  page223_i21
#CELL
  pure_quanta q_res *
  page223_i22
#ISCELL
  logical_power universal_power *
  page223_i23
#CELL
  pure_quanta q_res *
  page223_i24
#ISCELL
  logical_power universal_power *
  page223_i30
#CELL
  pure_quanta q_cap *
  page223_i31
#ISCELL
  logical_power universal_gnd *
  page223_i32
#ISCELL
  logical_power universal_power *
  page223_i33
#CELL
  pure_quanta q_res *
  page223_i34
#ISCELL
  logical_power universal_gnd *
  page223_i35
#ISCELL
  logical_power universal_power *
  page223_i37
#CELL
  pure_quanta q_res *
  page223_i38
#CELL
  pure_quanta pca9617adp *
  page223_i39
#ISCELL
  logical_power universal_gnd *
  page223_i40
#ISCELL
  logical_power universal_power *
  page223_i41
#CELL
  pure_quanta q_cap *
  page223_i42
#CELL
  pure_quanta pca9617adp *
  page223_i43
#ISCELL
  logical_power universal_gnd *
  page223_i44
#ISCELL
  logical_power universal_gnd *
  page223_i45
#CELL
  pure_quanta q_res *
  page223_i46
#ISCELL
  logical_power universal_power *
  page223_i47
#CELL
  pure_quanta q_res *
  page223_i48
#ISCELL
  standard offpage *
  page223_i5
#ISCELL
  logical_power universal_power *
  page223_i51
#CELL
  pure_quanta q_res *
  page223_i52
#CELL
  pure_quanta q_res *
  page223_i53
#ISCELL
  logical_power universal_power *
  page223_i54
#CELL
  pure_quanta q_res *
  page223_i55
#ISCELL
  standard offpage *
  page223_i56
#ISCELL
  standard offpage *
  page223_i57
#ISCELL
  standard offpage *
  page223_i58
#ISCELL
  standard offpage *
  page223_i59
#ISCELL
  standard offpage *
  page223_i6
#ISCELL
  standard offpage *
  page223_i60
#ISCELL
  standard offpage *
  page223_i61
#ISCELL
  standard offpage *
  page223_i62
#ISCELL
  logical_power universal_gnd *
  page223_i63
#CELL
  pure_quanta conn3_210hp1030br1 *
  page223_i64
#ISCELL
  logical_power universal_gnd *
  page223_i65
#ISCELL
  logical_power universal_gnd *
  page223_i67
#CELL
  pure_quanta q_res *
  page223_i69
#ISCELL
  logical_power universal_power *
  page223_i7
#ISCELL
  standard offpage *
  page223_i70
#CELL
  pure_quanta q_res *
  page223_i76
#CELL
  pure_quanta q_res *
  page223_i77
#ISCELL
  standard offpage *
  page223_i78
#ISCELL
  standard offpage *
  page223_i79
#CELL
  pure_quanta q_res *
  page223_i8
#ISCELL
  logical_power universal_power *
  page223_i80
#CELL
  pure_quanta q_res *
  page223_i81
#CELL
  pure_quanta q_res *
  page223_i82
#CELL
  pure_quanta q_res *
  page223_i88
#CELL
  pure_quanta q_res *
  page223_i89
#ISCELL
  standard offpage *
  page223_i90
#ISCELL
  standard offpage *
  page223_i91
#ISCELL
  logical_power universal_power *
  page223_i92
#CELL
  pure_quanta q_res *
  page223_i93
#CELL
  pure_quanta q_res *
  page223_i94
#CELL
  pure_quanta q_res *
  page223_i99
